# T6G (Grand Teton) — schematic netlist excerpt (pin names and nets, part order shuffled) for the footprints in the layout excerpt that follows; sources: Cadence DE-HDL packaged netlist, KiCad conversion of 04192023_DAF0TMB3IC0_F0TG_MB_C_brd_V02_OCP.brd

R679  Q_RES  33.2 1% CHIP  pkg 0201LF  page 289 : A = SMB_RT_CPU0_P1_ROM_R_SDA ; B = SMB_RT_CPU0_P1_ROM_SDA
R3662  Q_RES  0 5% CHIP  pkg 0402LF  page 234 : A = P3V3_AUX_USB_HUB ; B = USB_HUB_DVDD
R26  Q_RES  4.7K 5% EMPTY  pkg 0402LF  page 238 : A = P3V3_AUX ; B = SMB_FRU_3V3AUX_R1_SCL

(kicad_pcb
	(version 20260206)
	(generator "pcbnew")
	(generator_version "10.0")
	(general
		(thickness 1.6)
		(legacy_teardrops no)
	)
	(paper "A4")
	(title_block
		(title "04192023_DAF0TMB3IC0_F0TG_MB_C_brd_V02_OCP.brd")
		(comment 1 "Grand Teton / footprints 4752-4754 of 8354")
	)
	(layers
		(0 "F.Cu" signal "TOP")
		(4 "In1.Cu" signal "GND")
		(6 "In2.Cu" signal "IN1")
		(8 "In3.Cu" signal "GND1")
		(10 "In4.Cu" signal "IN2")
		(12 "In5.Cu" signal "GND2")
		(14 "In6.Cu" signal "IN3")
		(16 "In7.Cu" signal "GND3")
		(18 "In8.Cu" signal "VCC")
		(20 "In9.Cu" signal "VCC1")
		(22 "In10.Cu" signal "GND4")
		(24 "In11.Cu" signal "IN4")
		(26 "In12.Cu" signal "GND5")
		(28 "In13.Cu" signal "IN5")
		(30 "In14.Cu" signal "GND6")
		(32 "In15.Cu" signal "IN6")
		(34 "In16.Cu" signal "GND7")
		(2 "B.Cu" signal "BOTTOM")
		(9 "F.Adhes" user "F.Adhesive")
		(11 "B.Adhes" user "B.Adhesive")
		(13 "F.Paste" user "Package Geometry/Pastemask Top")
		(15 "B.Paste" user "Package Geometry/Pastemask Bottom")
		(5 "F.SilkS" user "Ref Des/Silkscreen Top")
		(7 "B.SilkS" user "Ref Des/Silkscreen Bottom")
		(1 "F.Mask" user "Board Geometry/Soldermask Top")
		(3 "B.Mask" user "Board Geometry/Soldermask Bottom")
		(17 "Dwgs.User" user "User.Drawings")
		(19 "Cmts.User" user "User.Comments")
		(21 "Eco1.User" user "User.Eco1")
		(23 "Eco2.User" user "User.Eco2")
		(25 "Edge.Cuts" user "Board Geometry/Outline")
		(27 "Margin" user)
		(31 "F.CrtYd" user "Package Geometry/Place Bound Top")
		(29 "B.CrtYd" user "Package Geometry/Place Bound Bottom")
		(35 "F.Fab" user "Ref Des/Assembly Top")
		(33 "B.Fab" user "Ref Des/Assembly Bottom")
	)
	(footprint ""
		(layer "F.Cu")
		(at 320.153538 -116.632228 180)
		(property "Reference" "R26"
			(at 0 0 180)
			(layer "F.SilkS")
			(hide yes)
			(effects
				(font
					(size 1.27 1.27)
				)
			)
		)
		(property "Value" ""
			(at 0 0 180)
			(layer "F.Fab")
			(effects
				(font
					(size 1.27 1.27)
				)
			)
		)
		(duplicate_pad_numbers_are_jumpers no)
		(fp_line
			(start 0.7874 0.4064)
			(end -0.7874 0.4064)
			(stroke
				(width 0.1524)
				(type default)
			)
			(layer "F.SilkS")
		)
		(fp_line
			(start 0.7874 -0.4064)
			(end 0.7874 0.4064)
			(stroke
				(width 0.1524)
				(type default)
			)
			(layer "F.SilkS")
		)
		(fp_line
			(start -0.7874 0.4064)
			(end -0.7874 -0.4064)
			(stroke
				(width 0.1524)
				(type default)
			)
			(layer "F.SilkS")
		)
		(fp_line
			(start -0.7874 -0.4064)
			(end 0.7874 -0.4064)
			(stroke
				(width 0.1524)
				(type default)
			)
			(layer "F.SilkS")
		)
		(fp_line
			(start 0.67945 0.3048)
			(end 0.120396 0.3048)
			(stroke
				(width 0.1)
				(type default)
			)
			(layer "F.Fab")
		)
		(fp_line
			(start 0.67945 -0.3048)
			(end 0.67945 0.3048)
			(stroke
				(width 0.1)
				(type default)
			)
			(layer "F.Fab")
		)
		(fp_line
			(start 0.12065 -0.2794)
			(end 0.12065 -0.3048)
			(stroke
				(width 0.1)
				(type default)
			)
			(layer "F.Fab")
		)
		(fp_line
			(start 0.12065 -0.3048)
			(end 0.67945 -0.3048)
			(stroke
				(width 0.1)
				(type default)
			)
			(layer "F.Fab")
		)
		(fp_line
			(start 0.120396 0.3048)
			(end 0.120396 0.2794)
			(stroke
				(width 0.1)
				(type default)
			)
			(layer "F.Fab")
		)
		(fp_line
			(start 0.120396 0.2794)
			(end -0.12065 0.2794)
			(stroke
				(width 0.1)
				(type default)
			)
			(layer "F.Fab")
		)
		(fp_line
			(start -0.12065 0.3048)
			(end -0.67945 0.3048)
			(stroke
				(width 0.1)
				(type default)
			)
			(layer "F.Fab")
		)
		(fp_line
			(start -0.12065 0.2794)
			(end -0.12065 0.3048)
			(stroke
				(width 0.1)
				(type default)
			)
			(layer "F.Fab")
		)
		(fp_line
			(start -0.12065 -0.2794)
			(end 0.12065 -0.2794)
			(stroke
				(width 0.1)
				(type default)
			)
			(layer "F.Fab")
		)
		(fp_line
			(start -0.12065 -0.305054)
			(end -0.12065 -0.2794)
			(stroke
				(width 0.1)
				(type default)
			)
			(layer "F.Fab")
		)
		(fp_line
			(start -0.67945 0.3048)
			(end -0.67945 -0.305054)
			(stroke
				(width 0.1)
				(type default)
			)
			(layer "F.Fab")
		)
		(fp_line
			(start -0.67945 -0.305054)
			(end -0.12065 -0.305054)
			(stroke
				(width 0.1)
				(type default)
			)
			(layer "F.Fab")
		)
		(pad "1" smd circle
			(at -0.40005 0 180)
			(size 0 0)
			(layers "F.Cu" "F.Mask" "F.Paste")
			(net "P3V3_AUX")
		)
		(pad "2" smd circle
			(at 0.40005 0 180)
			(size 0 0)
			(layers "F.Cu" "F.Mask" "F.Paste")
			(net "SMB_FRU_3V3AUX_R1_SCL")
		)
	)
	(footprint ""
		(layer "F.Cu")
		(at 17.190974 -92.687648 90)
		(property "Reference" "R3662"
			(at 0 0 90)
			(layer "F.SilkS")
			(hide yes)
			(effects
				(font
					(size 1.27 1.27)
				)
			)
		)
		(property "Value" ""
			(at 0 0 90)
			(layer "F.Fab")
			(effects
				(font
					(size 1.27 1.27)
				)
			)
		)
		(duplicate_pad_numbers_are_jumpers no)
		(fp_line
			(start 0.7874 -0.4064)
			(end 0.7874 0.4064)
			(stroke
				(width 0.1524)
				(type default)
			)
			(layer "F.SilkS")
		)
		(fp_line
			(start -0.7874 -0.4064)
			(end 0.7874 -0.4064)
			(stroke
				(width 0.1524)
				(type default)
			)
			(layer "F.SilkS")
		)
		(fp_line
			(start 0.7874 0.4064)
			(end -0.7874 0.4064)
			(stroke
				(width 0.1524)
				(type default)
			)
			(layer "F.SilkS")
		)
		(fp_line
			(start -0.7874 0.4064)
			(end -0.7874 -0.4064)
			(stroke
				(width 0.1524)
				(type default)
			)
			(layer "F.SilkS")
		)
		(fp_line
			(start -0.12065 -0.305054)
			(end -0.12065 -0.2794)
			(stroke
				(width 0.1)
				(type default)
			)
			(layer "F.Fab")
		)
		(fp_line
			(start -0.67945 -0.305054)
			(end -0.12065 -0.305054)
			(stroke
				(width 0.1)
				(type default)
			)
			(layer "F.Fab")
		)
		(fp_line
			(start 0.67945 -0.3048)
			(end 0.67945 0.3048)
			(stroke
				(width 0.1)
				(type default)
			)
			(layer "F.Fab")
		)
		(fp_line
			(start 0.12065 -0.3048)
			(end 0.67945 -0.3048)
			(stroke
				(width 0.1)
				(type default)
			)
			(layer "F.Fab")
		)
		(fp_line
			(start 0.12065 -0.2794)
			(end 0.12065 -0.3048)
			(stroke
				(width 0.1)
				(type default)
			)
			(layer "F.Fab")
		)
		(fp_line
			(start -0.12065 -0.2794)
			(end 0.12065 -0.2794)
			(stroke
				(width 0.1)
				(type default)
			)
			(layer "F.Fab")
		)
		(fp_line
			(start 0.120396 0.2794)
			(end -0.12065 0.2794)
			(stroke
				(width 0.1)
				(type default)
			)
			(layer "F.Fab")
		)
		(fp_line
			(start -0.12065 0.2794)
			(end -0.12065 0.3048)
			(stroke
				(width 0.1)
				(type default)
			)
			(layer "F.Fab")
		)
		(fp_line
			(start 0.67945 0.3048)
			(end 0.120396 0.3048)
			(stroke
				(width 0.1)
				(type default)
			)
			(layer "F.Fab")
		)
		(fp_line
			(start 0.120396 0.3048)
			(end 0.120396 0.2794)
			(stroke
				(width 0.1)
				(type default)
			)
			(layer "F.Fab")
		)
		(fp_line
			(start -0.12065 0.3048)
			(end -0.67945 0.3048)
			(stroke
				(width 0.1)
				(type default)
			)
			(layer "F.Fab")
		)
		(fp_line
			(start -0.67945 0.3048)
			(end -0.67945 -0.305054)
			(stroke
				(width 0.1)
				(type default)
			)
			(layer "F.Fab")
		)
		(pad "1" smd circle
			(at -0.40005 0 90)
			(size 0 0)
			(layers "F.Cu" "F.Mask" "F.Paste")
			(net "P3V3_AUX_USB_HUB")
		)
		(pad "2" smd circle
			(at 0.40005 0 90)
			(size 0 0)
			(layers "F.Cu" "F.Mask" "F.Paste")
			(net "USB_HUB_DVDD")
		)
	)
	(footprint ""
		(layer "F.Cu")
		(at 291.259006 -398.60855 90)
		(property "Reference" "R679"
			(at 0 0 90)
			(layer "F.SilkS")
			(hide yes)
			(effects
				(font
					(size 1.27 1.27)
				)
			)
		)
		(property "Value" ""
			(at 0 0 90)
			(layer "F.Fab")
			(effects
				(font
					(size 1.27 1.27)
				)
			)
		)
		(duplicate_pad_numbers_are_jumpers no)
		(fp_line
			(start 0.32512 -0.175006)
			(end 0.32512 0.175006)
			(stroke
				(width 0.1)
				(type default)
			)
			(layer "F.Fab")
		)
		(fp_line
			(start -0.32512 -0.175006)
			(end 0.32512 -0.175006)
			(stroke
				(width 0.1)
				(type default)
			)
			(layer "F.Fab")
		)
		(fp_line
			(start 0.32512 0.175006)
			(end -0.32512 0.175006)
			(stroke
				(width 0.1)
				(type default)
			)
			(layer "F.Fab")
		)
		(fp_line
			(start -0.32512 0.175006)
			(end -0.32512 -0.175006)
			(stroke
				(width 0.1)
				(type default)
			)
			(layer "F.Fab")
		)
		(pad "1" smd rect
			(at -0.2667 0 90)
			(size 0.3048 0.381)
			(layers "F.Cu" "F.Mask" "F.Paste")
			(net "SMB_RT_CPU0_P1_ROM_R_SDA")
		)
		(pad "2" smd rect
			(at 0.2667 0 270)
			(size 0.3048 0.381)
			(layers "F.Cu" "F.Mask" "F.Paste")
			(net "SMB_RT_CPU0_P1_ROM_SDA")
		)
	)
)
